(kicad_pcb
	(version 20260206)
	(generator "pcbnew")
	(generator_version "10.0")
	(general
		(thickness 1.6)
		(legacy_teardrops no)
	)
	(paper "A4")
	(title_block
		(title "Wiwynn_Tioga_Pass_MB.brd")
		(comment 1 "Tioga Pass / footprints 4145-4151 of 4770")
	)
	(layers
		(0 "F.Cu" signal "TOP")
		(4 "In1.Cu" signal "L2GND")
		(6 "In2.Cu" signal "L3")
		(8 "In3.Cu" signal "L4GND")
		(10 "In4.Cu" signal "L5")
		(12 "In5.Cu" signal "L6GND")
		(14 "In6.Cu" signal "L7VCC")
		(16 "In7.Cu" signal "L8VCC")
		(18 "In8.Cu" signal "L9GND")
		(20 "In9.Cu" signal "L10")
		(22 "In10.Cu" signal "L11GND")
		(24 "In11.Cu" signal "L12")
		(26 "In12.Cu" signal "L13GND")
		(2 "B.Cu" signal "BOTTOM")
		(9 "F.Adhes" user "F.Adhesive")
		(11 "B.Adhes" user "B.Adhesive")
		(13 "F.Paste" user "Package Geometry/Pastemask Top")
		(15 "B.Paste" user "Package Geometry/Pastemask Bottom")
		(5 "F.SilkS" user "Ref Des/Silkscreen Top")
		(7 "B.SilkS" user "Ref Des/Silkscreen Bottom")
		(1 "F.Mask" user "Board Geometry/Soldermask Top")
		(3 "B.Mask" user "Board Geometry/Soldermask Bottom")
		(17 "Dwgs.User" user "User.Drawings")
		(19 "Cmts.User" user "User.Comments")
		(21 "Eco1.User" user "User.Eco1")
		(23 "Eco2.User" user "User.Eco2")
		(25 "Edge.Cuts" user "Board Geometry/Outline")
		(27 "Margin" user)
		(31 "F.CrtYd" user "Package Geometry/Place Bound Top")
		(29 "B.CrtYd" user "Package Geometry/Place Bound Bottom")
		(35 "F.Fab" user "Ref Des/Assembly Top")
		(33 "B.Fab" user "Ref Des/Assembly Bottom")
	)
	(footprint ""
		(layer "B.Cu")
		(at 272.861532 -145.0086 90)
		(property "Reference" "C5L7"
			(at -1.848866 0.752348 90)
			(unlocked yes)
			(layer "B.SilkS")
			(effects
				(font
					(size 1.27 0.9652)
					(thickness 0.1524)
				)
				(justify mirror)
			)
		)
		(property "Value" ""
			(at 0 0 90)
			(layer "B.Fab")
			(effects
				(font
					(size 1.27 1.27)
				)
				(justify mirror)
			)
		)
		(duplicate_pad_numbers_are_jumpers no)
		(fp_rect
			(start 0.500126 1.598422)
			(end -0.500126 -0.201422)
			(stroke
				(width 0)
				(type default)
			)
			(fill no)
			(layer "B.CrtYd")
		)
		(fp_line
			(start 0.500126 -0.201422)
			(end -0.500126 -0.201422)
			(stroke
				(width 0.1)
				(type default)
			)
			(layer "B.Fab")
		)
		(fp_line
			(start -0.500126 -0.201422)
			(end -0.500126 1.598422)
			(stroke
				(width 0.1)
				(type default)
			)
			(layer "B.Fab")
		)
		(fp_line
			(start 0.500126 1.598422)
			(end 0.500126 -0.201422)
			(stroke
				(width 0.1)
				(type default)
			)
			(layer "B.Fab")
		)
		(fp_line
			(start -0.500126 1.598422)
			(end 0.500126 1.598422)
			(stroke
				(width 0.1)
				(type default)
			)
			(layer "B.Fab")
		)
		(pad "1" smd rect
			(at 0 0)
			(size 0.889 0.9906)
			(layers "B.Cu" "B.Mask" "B.Paste")
			(net "PVDDQ_DEF")
		)
		(pad "2" smd rect
			(at 0 1.397)
			(size 0.889 0.9906)
			(layers "B.Cu" "B.Mask" "B.Paste")
			(net "GND")
		)
		(zone
			(layer "B.Cu")
			(hatch none 0.5)
			(connect_pads
				(clearance 0)
			)
			(min_thickness 0.25)
			(keepout
				(tracks not_allowed)
				(vias allowed)
				(pads allowed)
				(copperpour not_allowed)
				(footprints allowed)
			)
			(placement
				(enabled no)
				(sheetname "")
			)
			(fill
				(thermal_gap 0.5)
				(thermal_bridge_width 0.5)
				(island_removal_mode 0)
			)
			(polygon
				(pts
					(xy 273.814032 -145.5039) (xy 273.306032 -145.5039) (xy 273.306032 -144.5133) (xy 273.814032 -144.5133)
				)
			)
		)
		(zone
			(layer "B.Cu")
			(hatch none 0.5)
			(connect_pads
				(clearance 0)
			)
			(min_thickness 0.25)
			(keepout
				(tracks allowed)
				(vias not_allowed)
				(pads allowed)
				(copperpour not_allowed)
				(footprints allowed)
			)
			(placement
				(enabled no)
				(sheetname "")
			)
			(fill
				(thermal_gap 0.5)
				(thermal_bridge_width 0.5)
				(island_removal_mode 0)
			)
			(polygon
				(pts
					(xy 273.814032 -145.5039) (xy 273.306032 -145.5039) (xy 273.306032 -144.5133) (xy 273.814032 -144.5133)
				)
			)
		)
	)
	(footprint ""
		(layer "B.Cu")
		(at 162.91306 -84.328 90)
		(property "Reference" "R7P2"
			(at 0 0 90)
			(layer "B.SilkS")
			(hide yes)
			(effects
				(font
					(size 1.27 1.27)
				)
				(justify mirror)
			)
		)
		(property "Value" ""
			(at 0 0 90)
			(layer "B.Fab")
			(effects
				(font
					(size 1.27 1.27)
				)
				(justify mirror)
			)
		)
		(duplicate_pad_numbers_are_jumpers no)
		(fp_poly
			(pts
				(xy 0.2794 -0.1016) (xy -0.2794 -0.1016) (xy -0.2794 0.9906) (xy 0.2794 0.9906)
			)
			(stroke
				(width 0)
				(type default)
			)
			(fill no)
			(layer "B.CrtYd")
		)
		(fp_line
			(start 0.2794 -0.1016)
			(end 0.2794 0.9906)
			(stroke
				(width 0.1)
				(type default)
			)
			(layer "B.Fab")
		)
		(fp_line
			(start -0.2794 -0.1016)
			(end 0.2794 -0.1016)
			(stroke
				(width 0.1)
				(type default)
			)
			(layer "B.Fab")
		)
		(fp_line
			(start 0.2794 0.9906)
			(end -0.2794 0.9906)
			(stroke
				(width 0.1)
				(type default)
			)
			(layer "B.Fab")
		)
		(fp_line
			(start -0.2794 0.9906)
			(end -0.2794 -0.1016)
			(stroke
				(width 0.1)
				(type default)
			)
			(layer "B.Fab")
		)
		(pad "1" smd rect
			(at 0 0 270)
			(size 0.508 0.508)
			(layers "B.Cu" "B.Mask" "B.Paste")
			(net "CLK_100M_CPU1_BCLK2_DN")
		)
		(pad "2" smd rect
			(at 0 0.889 270)
			(size 0.508 0.508)
			(layers "B.Cu" "B.Mask" "B.Paste")
			(net "GND")
		)
		(zone
			(layer "B.Cu")
			(hatch none 0.5)
			(connect_pads
				(clearance 0)
			)
			(min_thickness 0.25)
			(keepout
				(tracks allowed)
				(vias not_allowed)
				(pads allowed)
				(copperpour not_allowed)
				(footprints allowed)
			)
			(placement
				(enabled no)
				(sheetname "")
			)
			(fill
				(thermal_gap 0.5)
				(thermal_bridge_width 0.5)
				(island_removal_mode 0)
			)
			(polygon
				(pts
					(xy 163.16706 -84.582) (xy 163.16706 -84.074) (xy 163.54806 -84.074) (xy 163.54806 -84.582)
				)
			)
		)
		(zone
			(layer "B.Cu")
			(hatch none 0.5)
			(connect_pads
				(clearance 0)
			)
			(min_thickness 0.25)
			(keepout
				(tracks not_allowed)
				(vias allowed)
				(pads allowed)
				(copperpour not_allowed)
				(footprints allowed)
			)
			(placement
				(enabled no)
				(sheetname "")
			)
			(fill
				(thermal_gap 0.5)
				(thermal_bridge_width 0.5)
				(island_removal_mode 0)
			)
			(polygon
				(pts
					(xy 163.54806 -84.582) (xy 163.54806 -84.074) (xy 163.16706 -84.074) (xy 163.16706 -84.582)
				)
			)
		)
	)
	(footprint ""
		(layer "B.Cu")
		(at 350.024192 -77.834236)
		(property "Reference" "C3P26"
			(at 0 0 0)
			(layer "B.SilkS")
			(hide yes)
			(effects
				(font
					(size 1.27 1.27)
				)
				(justify mirror)
			)
		)
		(property "Value" ""
			(at 0 0 0)
			(layer "B.Fab")
			(effects
				(font
					(size 1.27 1.27)
				)
				(justify mirror)
			)
		)
		(duplicate_pad_numbers_are_jumpers no)
		(fp_poly
			(pts
				(xy -0.3048 -0.1016) (xy -0.3048 0.9906) (xy 0.3048 0.9906) (xy 0.3048 -0.1016)
			)
			(stroke
				(width 0)
				(type default)
			)
			(fill no)
			(layer "B.CrtYd")
		)
		(fp_line
			(start -0.3048 -0.1016)
			(end 0.3048 -0.1016)
			(stroke
				(width 0.1)
				(type default)
			)
			(layer "B.Fab")
		)
		(fp_line
			(start -0.3048 0.9906)
			(end -0.3048 -0.1016)
			(stroke
				(width 0.1)
				(type default)
			)
			(layer "B.Fab")
		)
		(fp_line
			(start 0.3048 -0.1016)
			(end 0.3048 0.9906)
			(stroke
				(width 0.1)
				(type default)
			)
			(layer "B.Fab")
		)
		(fp_line
			(start 0.3048 0.9906)
			(end -0.3048 0.9906)
			(stroke
				(width 0.1)
				(type default)
			)
			(layer "B.Fab")
		)
		(pad "1" smd rect
			(at 0 0 180)
			(size 0.508 0.508)
			(layers "B.Cu" "B.Mask" "B.Paste")
			(net "P3E_CPU0_PE1_SS_TXP<4>")
		)
		(pad "2" smd rect
			(at 0 0.889 180)
			(size 0.508 0.508)
			(layers "B.Cu" "B.Mask" "B.Paste")
			(net "P3E_CPU0_PE1_SS_C_TXP<4>")
		)
		(zone
			(layer "B.Cu")
			(hatch none 0.5)
			(connect_pads
				(clearance 0)
			)
			(min_thickness 0.25)
			(keepout
				(tracks allowed)
				(vias not_allowed)
				(pads allowed)
				(copperpour not_allowed)
				(footprints allowed)
			)
			(placement
				(enabled no)
				(sheetname "")
			)
			(fill
				(thermal_gap 0.5)
				(thermal_bridge_width 0.5)
				(island_removal_mode 0)
			)
			(polygon
				(pts
					(xy 350.278192 -77.580236) (xy 349.770192 -77.580236) (xy 349.770192 -77.199236) (xy 350.278192 -77.199236)
				)
			)
		)
		(zone
			(layer "B.Cu")
			(hatch none 0.5)
			(connect_pads
				(clearance 0)
			)
			(min_thickness 0.25)
			(keepout
				(tracks not_allowed)
				(vias allowed)
				(pads allowed)
				(copperpour not_allowed)
				(footprints allowed)
			)
			(placement
				(enabled no)
				(sheetname "")
			)
			(fill
				(thermal_gap 0.5)
				(thermal_bridge_width 0.5)
				(island_removal_mode 0)
			)
			(polygon
				(pts
					(xy 350.278192 -77.199236) (xy 349.770192 -77.199236) (xy 349.770192 -77.580236) (xy 350.278192 -77.580236)
				)
			)
		)
	)
	(footprint ""
		(layer "B.Cu")
		(at 442.468 -157.1498)
		(property "Reference" "U25W17"
			(at 0.14986 2.621788 0)
			(unlocked yes)
			(layer "B.SilkS")
			(effects
				(font
					(size 1.27 0.964946)
					(thickness 0.000001)
				)
				(justify left mirror)
			)
		)
		(property "Value" ""
			(at 0 0 0)
			(layer "B.Fab")
			(effects
				(font
					(size 1.27 1.27)
				)
				(justify mirror)
			)
		)
		(duplicate_pad_numbers_are_jumpers no)
		(fp_circle
			(center 0.4699 -0.8382)
			(end 0.5969 -0.8382)
			(stroke
				(width 0.254)
				(type default)
			)
			(fill no)
			(layer "B.SilkS")
		)
		(fp_poly
			(pts
				(xy -0.21463 -0.450088) (xy -1.56337 -0.450088) (xy -1.56337 1.75006) (xy -0.21463 1.75006)
			)
			(stroke
				(width 0)
				(type default)
			)
			(fill no)
			(layer "B.CrtYd")
		)
		(fp_line
			(start -1.56337 -0.450088)
			(end -1.56337 1.75006)
			(stroke
				(width 0.1)
				(type default)
			)
			(layer "B.Fab")
		)
		(fp_line
			(start -1.56337 1.75006)
			(end -0.21463 1.75006)
			(stroke
				(width 0.1)
				(type default)
			)
			(layer "B.Fab")
		)
		(fp_line
			(start -0.21463 -0.450088)
			(end -1.56337 -0.450088)
			(stroke
				(width 0.1)
				(type default)
			)
			(layer "B.Fab")
		)
		(fp_line
			(start -0.21463 1.75006)
			(end -0.21463 -0.450088)
			(stroke
				(width 0.1)
				(type default)
			)
			(layer "B.Fab")
		)
		(fp_circle
			(center 0.4699 -0.8382)
			(end 0.5969 -0.8382)
			(stroke
				(width 0.254)
				(type default)
			)
			(fill no)
			(layer "B.Fab")
		)
		(pad "1" smd rect
			(at 0 0 180)
			(size 1.016 0.381)
			(layers "B.Cu" "B.Mask" "B.Paste")
			(net "JTAG_BMC_TRST_N")
		)
		(pad "2" smd rect
			(at 0 0.649986 180)
			(size 1.016 0.381)
			(layers "B.Cu" "B.Mask" "B.Paste")
			(net "BMC_JTAG_SEL_BUF")
		)
		(pad "3" smd rect
			(at 0 1.299972 180)
			(size 1.016 0.381)
			(layers "B.Cu" "B.Mask" "B.Paste")
			(net "GND")
		)
		(pad "4" smd rect
			(at -1.778 1.299972 180)
			(size 1.016 0.381)
			(layers "B.Cu" "B.Mask" "B.Paste")
			(net "JTAG_BMC_TRST_BUF_N")
		)
		(pad "5" smd rect
			(at -1.778 0 180)
			(size 1.016 0.381)
			(layers "B.Cu" "B.Mask" "B.Paste")
			(net "P3V3_STBY")
		)
	)
	(footprint ""
		(layer "B.Cu")
		(at 372.980966 -72.678036 180)
		(property "Reference" "C3P51"
			(at 0 0 0)
			(layer "B.SilkS")
			(hide yes)
			(effects
				(font
					(size 1.27 1.27)
				)
				(justify mirror)
			)
		)
		(property "Value" ""
			(at 0 0 0)
			(layer "B.Fab")
			(effects
				(font
					(size 1.27 1.27)
				)
				(justify mirror)
			)
		)
		(duplicate_pad_numbers_are_jumpers no)
		(fp_rect
			(start 0.2794 0.9144)
			(end -0.2794 -0.1143)
			(stroke
				(width 0)
				(type default)
			)
			(fill no)
			(layer "B.CrtYd")
		)
		(fp_line
			(start 0.2794 0.9144)
			(end 0.2794 -0.1143)
			(stroke
				(width 0.1)
				(type default)
			)
			(layer "B.Fab")
		)
		(fp_line
			(start 0.2794 -0.1143)
			(end -0.2794 -0.1143)
			(stroke
				(width 0.1)
				(type default)
			)
			(layer "B.Fab")
		)
		(fp_line
			(start -0.2794 0.9144)
			(end 0.2794 0.9144)
			(stroke
				(width 0.1)
				(type default)
			)
			(layer "B.Fab")
		)
		(fp_line
			(start -0.2794 -0.1143)
			(end -0.2794 0.9144)
			(stroke
				(width 0.1)
				(type default)
			)
			(layer "B.Fab")
		)
		(pad "1" smd custom
			(at 0 0 90)
			(size 0.10414 0.10414)
			(layers "B.Cu" "B.Mask" "B.Paste")
			(net "P3V3_STBY")
			(options
				(clearance outline)
				(anchor circle)
			)
			(primitives
				(gr_poly
					(pts
						(xy -0.20828 -0.08636) (xy -0.20828 0.08636) (xy -0.08636 0.20828) (xy 0.086614 0.20828) (xy 0.20828 0.086614)
						(xy 0.20828 -0.08636) (xy 0.08636 -0.20828) (xy -0.08636 -0.20828)
					)
					(width 0)
					(fill yes)
				)
			)
		)
		(pad "2" smd custom
			(at 0 0.8001 90)
			(size 0.10414 0.10414)
			(layers "B.Cu" "B.Mask" "B.Paste")
			(net "GND")
			(options
				(clearance outline)
				(anchor circle)
			)
			(primitives
				(gr_poly
					(pts
						(xy -0.20828 -0.08636) (xy -0.20828 0.08636) (xy -0.08636 0.20828) (xy 0.086614 0.20828) (xy 0.20828 0.086614)
						(xy 0.20828 -0.08636) (xy 0.08636 -0.20828) (xy -0.08636 -0.20828)
					)
					(width 0)
					(fill yes)
				)
			)
		)
		(zone
			(layer "B.Cu")
			(hatch none 0.5)
			(connect_pads
				(clearance 0)
			)
			(min_thickness 0.25)
			(keepout
				(tracks allowed)
				(vias not_allowed)
				(pads allowed)
				(copperpour not_allowed)
				(footprints allowed)
			)
			(placement
				(enabled no)
				(sheetname "")
			)
			(fill
				(thermal_gap 0.5)
				(thermal_bridge_width 0.5)
				(island_removal_mode 0)
			)
			(polygon
				(pts
					(xy 372.893336 -72.887586) (xy 372.893336 -73.268586) (xy 373.068596 -73.268586) (xy 373.06885 -72.887586)
				)
			)
		)
		(zone
			(layer "B.Cu")
			(hatch none 0.5)
			(connect_pads
				(clearance 0)
			)
			(min_thickness 0.25)
			(keepout
				(tracks not_allowed)
				(vias allowed)
				(pads allowed)
				(copperpour not_allowed)
				(footprints allowed)
			)
			(placement
				(enabled no)
				(sheetname "")
			)
			(fill
				(thermal_gap 0.5)
				(thermal_bridge_width 0.5)
				(island_removal_mode 0)
			)
			(polygon
				(pts
					(xy 372.893336 -72.887586) (xy 372.893336 -73.268586) (xy 373.068596 -73.268586) (xy 373.06885 -72.887586)
				)
			)
		)
	)
	(footprint ""
		(layer "B.Cu")
		(at 365.506 -112.395 -90)
		(property "Reference" "C3M45"
			(at 0 0 90)
			(layer "B.SilkS")
			(hide yes)
			(effects
				(font
					(size 1.27 1.27)
				)
				(justify mirror)
			)
		)
		(property "Value" ""
			(at 0 0 90)
			(layer "B.Fab")
			(effects
				(font
					(size 1.27 1.27)
				)
				(justify mirror)
			)
		)
		(duplicate_pad_numbers_are_jumpers no)
		(fp_poly
			(pts
				(xy -0.3048 -0.1016) (xy -0.3048 0.9906) (xy 0.3048 0.9906) (xy 0.3048 -0.1016)
			)
			(stroke
				(width 0)
				(type default)
			)
			(fill no)
			(layer "B.CrtYd")
		)
		(fp_line
			(start -0.3048 0.9906)
			(end -0.3048 -0.1016)
			(stroke
				(width 0.1)
				(type default)
			)
			(layer "B.Fab")
		)
		(fp_line
			(start 0.3048 0.9906)
			(end -0.3048 0.9906)
			(stroke
				(width 0.1)
				(type default)
			)
			(layer "B.Fab")
		)
		(fp_line
			(start -0.3048 -0.1016)
			(end 0.3048 -0.1016)
			(stroke
				(width 0.1)
				(type default)
			)
			(layer "B.Fab")
		)
		(fp_line
			(start 0.3048 -0.1016)
			(end 0.3048 0.9906)
			(stroke
				(width 0.1)
				(type default)
			)
			(layer "B.Fab")
		)
		(pad "1" smd rect
			(at 0 0 90)
			(size 0.508 0.508)
			(layers "B.Cu" "B.Mask" "B.Paste")
			(net "DMI_CPU0_PCH_RX_DN<2>")
		)
		(pad "2" smd rect
			(at 0 0.889 90)
			(size 0.508 0.508)
			(layers "B.Cu" "B.Mask" "B.Paste")
			(net "DMI_CPU0_PCH_RX_C_DN<2>")
		)
		(zone
			(layer "B.Cu")
			(hatch none 0.5)
			(connect_pads
				(clearance 0)
			)
			(min_thickness 0.25)
			(keepout
				(tracks not_allowed)
				(vias allowed)
				(pads allowed)
				(copperpour not_allowed)
				(footprints allowed)
			)
			(placement
				(enabled no)
				(sheetname "")
			)
			(fill
				(thermal_gap 0.5)
				(thermal_bridge_width 0.5)
				(island_removal_mode 0)
			)
			(polygon
				(pts
					(xy 364.871 -112.141) (xy 364.871 -112.649) (xy 365.252 -112.649) (xy 365.252 -112.141)
				)
			)
		)
		(zone
			(layer "B.Cu")
			(hatch none 0.5)
			(connect_pads
				(clearance 0)
			)
			(min_thickness 0.25)
			(keepout
				(tracks allowed)
				(vias not_allowed)
				(pads allowed)
				(copperpour not_allowed)
				(footprints allowed)
			)
			(placement
				(enabled no)
				(sheetname "")
			)
			(fill
				(thermal_gap 0.5)
				(thermal_bridge_width 0.5)
				(island_removal_mode 0)
			)
			(polygon
				(pts
					(xy 365.252 -112.141) (xy 365.252 -112.649) (xy 364.871 -112.649) (xy 364.871 -112.141)
				)
			)
		)
	)
	(footprint ""
		(layer "B.Cu")
		(at 399.2372 -87.4522 180)
		(property "Reference" "R8W6"
			(at 0.8382 -0.67818 180)
			(unlocked yes)
			(layer "B.SilkS")
			(effects
				(font
					(size 0.4064 0.254)
					(thickness 0.1524)
				)
				(justify left mirror)
			)
		)
		(property "Value" ""
			(at 0 0 0)
			(layer "B.Fab")
			(effects
				(font
					(size 1.27 1.27)
				)
				(justify mirror)
			)
		)
		(duplicate_pad_numbers_are_jumpers no)
		(fp_poly
			(pts
				(xy 0.2794 -0.1016) (xy -0.2794 -0.1016) (xy -0.2794 0.9906) (xy 0.2794 0.9906)
			)
			(stroke
				(width 0)
				(type default)
			)
			(fill no)
			(layer "B.CrtYd")
		)
		(fp_line
			(start 0.2794 0.9906)
			(end -0.2794 0.9906)
			(stroke
				(width 0.1)
				(type default)
			)
			(layer "B.Fab")
		)
		(fp_line
			(start 0.2794 -0.1016)
			(end 0.2794 0.9906)
			(stroke
				(width 0.1)
				(type default)
			)
			(layer "B.Fab")
		)
		(fp_line
			(start -0.2794 0.9906)
			(end -0.2794 -0.1016)
			(stroke
				(width 0.1)
				(type default)
			)
			(layer "B.Fab")
		)
		(fp_line
			(start -0.2794 -0.1016)
			(end 0.2794 -0.1016)
			(stroke
				(width 0.1)
				(type default)
			)
			(layer "B.Fab")
		)
		(pad "1" smd rect
			(at 0 0)
			(size 0.508 0.508)
			(layers "B.Cu" "B.Mask" "B.Paste")
			(net "P3V3_STBY")
		)
		(pad "2" smd rect
			(at 0 0.889)
			(size 0.508 0.508)
			(layers "B.Cu" "B.Mask" "B.Paste")
			(net "SMB_VR_STBY_LVC3_SDA_R1")
		)
		(zone
			(layer "B.Cu")
			(hatch none 0.5)
			(connect_pads
				(clearance 0)
			)
			(min_thickness 0.25)
			(keepout
				(tracks not_allowed)
				(vias allowed)
				(pads allowed)
				(copperpour not_allowed)
				(footprints allowed)
			)
			(placement
				(enabled no)
				(sheetname "")
			)
			(fill
				(thermal_gap 0.5)
				(thermal_bridge_width 0.5)
				(island_removal_mode 0)
			)
			(polygon
				(pts
					(xy 398.9832 -88.0872) (xy 399.4912 -88.0872) (xy 399.4912 -87.7062) (xy 398.9832 -87.7062)
				)
			)
		)
		(zone
			(layer "B.Cu")
			(hatch none 0.5)
			(connect_pads
				(clearance 0)
			)
			(min_thickness 0.25)
			(keepout
				(tracks allowed)
				(vias not_allowed)
				(pads allowed)
				(copperpour not_allowed)
				(footprints allowed)
			)
			(placement
				(enabled no)
				(sheetname "")
			)
			(fill
				(thermal_gap 0.5)
				(thermal_bridge_width 0.5)
				(island_removal_mode 0)
			)
			(polygon
				(pts
					(xy 398.9832 -87.7062) (xy 399.4912 -87.7062) (xy 399.4912 -88.0872) (xy 398.9832 -88.0872)
				)
			)
		)
	)
)
